# BASEBOARD_FAB2 (Tioga Pass) — schematic netlist excerpt (pin names and nets, part order shuffled) for the footprints in the layout excerpt that follows; sources: Cadence DE-HDL packaged netlist, KiCad conversion of Wiwynn_Tioga_Pass_MB.brd

R6W43  RES  4.75K 1% EMPTY  pkg 0402  page 164 : A = P3V3_STBY ; B = PCA9554_A1
C5D28  CAP_A  22.0UF 4V 20% X6S  pkg 0603V  page 42 : A = PVCCIN_CPU0 ; B = GND
L7C1  IND-100NH-35-GP  pkg DISCRET-G8  page 212 : S = P12V_STBY ; F = VR_FET_SW_P12V_STBY_PVCCIO_CPU0

(kicad_pcb
	(version 20260206)
	(generator "pcbnew")
	(generator_version "10.0")
	(general
		(thickness 1.6)
		(legacy_teardrops no)
	)
	(paper "A4")
	(title_block
		(title "Wiwynn_Tioga_Pass_MB.brd")
		(comment 1 "Tioga Pass / footprints 1785-1787 of 4770")
	)
	(layers
		(0 "F.Cu" signal "TOP")
		(4 "In1.Cu" signal "L2GND")
		(6 "In2.Cu" signal "L3")
		(8 "In3.Cu" signal "L4GND")
		(10 "In4.Cu" signal "L5")
		(12 "In5.Cu" signal "L6GND")
		(14 "In6.Cu" signal "L7VCC")
		(16 "In7.Cu" signal "L8VCC")
		(18 "In8.Cu" signal "L9GND")
		(20 "In9.Cu" signal "L10")
		(22 "In10.Cu" signal "L11GND")
		(24 "In11.Cu" signal "L12")
		(26 "In12.Cu" signal "L13GND")
		(2 "B.Cu" signal "BOTTOM")
		(9 "F.Adhes" user "F.Adhesive")
		(11 "B.Adhes" user "B.Adhesive")
		(13 "F.Paste" user "Package Geometry/Pastemask Top")
		(15 "B.Paste" user "Package Geometry/Pastemask Bottom")
		(5 "F.SilkS" user "Ref Des/Silkscreen Top")
		(7 "B.SilkS" user "Ref Des/Silkscreen Bottom")
		(1 "F.Mask" user "Board Geometry/Soldermask Top")
		(3 "B.Mask" user "Board Geometry/Soldermask Bottom")
		(17 "Dwgs.User" user "User.Drawings")
		(19 "Cmts.User" user "User.Comments")
		(21 "Eco1.User" user "User.Eco1")
		(23 "Eco2.User" user "User.Eco2")
		(25 "Edge.Cuts" user "Board Geometry/Outline")
		(27 "Margin" user)
		(31 "F.CrtYd" user "Package Geometry/Place Bound Top")
		(29 "B.CrtYd" user "Package Geometry/Place Bound Bottom")
		(35 "F.Fab" user "Ref Des/Assembly Top")
		(33 "B.Fab" user "Ref Des/Assembly Bottom")
	)
	(footprint ""
		(layer "F.Cu")
		(at 434.7718 -14.859 180)
		(property "Reference" "R6W43"
			(at -0.8382 -0.67818 180)
			(unlocked yes)
			(layer "F.SilkS")
			(effects
				(font
					(size 0.4064 0.254)
					(thickness 0.1524)
				)
				(justify left)
			)
		)
		(property "Value" ""
			(at 0 0 180)
			(layer "F.Fab")
			(effects
				(font
					(size 1.27 1.27)
				)
			)
		)
		(duplicate_pad_numbers_are_jumpers no)
		(fp_poly
			(pts
				(xy -0.2794 -0.1016) (xy 0.2794 -0.1016) (xy 0.2794 0.9906) (xy -0.2794 0.9906)
			)
			(stroke
				(width 0)
				(type default)
			)
			(fill no)
			(layer "F.CrtYd")
		)
		(fp_line
			(start 0.2794 0.9906)
			(end 0.2794 -0.1016)
			(stroke
				(width 0.1)
				(type default)
			)
			(layer "F.Fab")
		)
		(fp_line
			(start 0.2794 -0.1016)
			(end -0.2794 -0.1016)
			(stroke
				(width 0.1)
				(type default)
			)
			(layer "F.Fab")
		)
		(fp_line
			(start -0.2794 0.9906)
			(end 0.2794 0.9906)
			(stroke
				(width 0.1)
				(type default)
			)
			(layer "F.Fab")
		)
		(fp_line
			(start -0.2794 -0.1016)
			(end -0.2794 0.9906)
			(stroke
				(width 0.1)
				(type default)
			)
			(layer "F.Fab")
		)
		(pad "1" smd rect
			(at 0 0 180)
			(size 0.508 0.508)
			(layers "F.Cu" "F.Mask" "F.Paste")
			(net "P3V3_STBY")
		)
		(pad "2" smd rect
			(at 0 0.889 180)
			(size 0.508 0.508)
			(layers "F.Cu" "F.Mask" "F.Paste")
			(net "PCA9554_A1")
		)
		(zone
			(layer "F.Cu")
			(hatch none 0.5)
			(connect_pads
				(clearance 0)
			)
			(min_thickness 0.25)
			(keepout
				(tracks not_allowed)
				(vias allowed)
				(pads allowed)
				(copperpour not_allowed)
				(footprints allowed)
			)
			(placement
				(enabled no)
				(sheetname "")
			)
			(fill
				(thermal_gap 0.5)
				(thermal_bridge_width 0.5)
				(island_removal_mode 0)
			)
			(polygon
				(pts
					(xy 435.0258 -15.494) (xy 434.5178 -15.494) (xy 434.5178 -15.113) (xy 435.0258 -15.113)
				)
			)
		)
		(zone
			(layer "F.Cu")
			(hatch none 0.5)
			(connect_pads
				(clearance 0)
			)
			(min_thickness 0.25)
			(keepout
				(tracks allowed)
				(vias not_allowed)
				(pads allowed)
				(copperpour not_allowed)
				(footprints allowed)
			)
			(placement
				(enabled no)
				(sheetname "")
			)
			(fill
				(thermal_gap 0.5)
				(thermal_bridge_width 0.5)
				(island_removal_mode 0)
			)
			(polygon
				(pts
					(xy 435.0258 -15.113) (xy 434.5178 -15.113) (xy 434.5178 -15.494) (xy 435.0258 -15.494)
				)
			)
		)
	)
	(footprint ""
		(layer "F.Cu")
		(at 352.714814 -103.103934 -90)
		(property "Reference" "L7C1"
			(at 0 0 270)
			(layer "F.SilkS")
			(hide yes)
			(effects
				(font
					(size 1.27 1.27)
				)
			)
		)
		(property "Value" "*"
			(at -3.5941 0.3429 270)
			(unlocked yes)
			(layer "F.Fab")
			(hide yes)
			(effects
				(font
					(size 1.27 1.016)
					(thickness 0.1524)
				)
			)
		)
		(property "Device Type" "IND-100NH-35-GP_DISCRET-G8-INDA"
			(at -3.5941 -1.1811 270)
			(unlocked yes)
			(layer "F.Fab")
			(hide yes)
			(effects
				(font
					(size 1.27 1.016)
					(thickness 0.1524)
				)
			)
		)
		(duplicate_pad_numbers_are_jumpers no)
		(fp_line
			(start -2.2479 2.794)
			(end -2.2479 -2.794)
			(stroke
				(width 0.1524)
				(type default)
			)
			(layer "F.SilkS")
		)
		(fp_line
			(start 2.2479 2.794)
			(end -2.2479 2.794)
			(stroke
				(width 0.1524)
				(type default)
			)
			(layer "F.SilkS")
		)
		(fp_line
			(start -2.2479 -2.794)
			(end 2.2479 -2.794)
			(stroke
				(width 0.1524)
				(type default)
			)
			(layer "F.SilkS")
		)
		(fp_line
			(start 2.2479 -2.794)
			(end 2.2479 2.794)
			(stroke
				(width 0.1524)
				(type default)
			)
			(layer "F.SilkS")
		)
		(fp_poly
			(pts
				(xy -1.9939 1.9939) (xy 1.9939 1.9939) (xy 1.9939 -1.9939) (xy -1.9939 -1.9939)
			)
			(stroke
				(width 0)
				(type default)
			)
			(fill no)
			(layer "F.CrtYd")
		)
		(fp_poly
			(pts
				(xy -2.5019 2.8702) (xy -2.5019 1.9939) (xy 1.9939 1.9939) (xy 1.9939 -1.9939) (xy -1.9939 -1.9939)
				(xy -1.9939 1.9812) (xy -2.5019 1.9812) (xy -2.5019 -2.8702) (xy 2.5019 -2.8702) (xy 2.5019 2.8702)
			)
			(stroke
				(width 0)
				(type default)
			)
			(fill no)
			(layer "F.CrtYd")
		)
		(fp_rect
			(start -2.5019 2.8702)
			(end 2.5019 -2.8702)
			(stroke
				(width 0)
				(type default)
			)
			(fill no)
			(layer "F.Fab")
		)
		(pad "1" smd rect
			(at 0 -1.745996 270)
			(size 1.5494 1.6002)
			(layers "F.Cu" "F.Mask" "F.Paste")
			(net "P12V_STBY")
		)
		(pad "2" smd rect
			(at 0 1.745996 270)
			(size 1.5494 1.6002)
			(layers "F.Cu" "F.Mask" "F.Paste")
			(net "VR_FET_SW_P12V_STBY_PVCCIO_CPU0")
		)
	)
	(footprint ""
		(layer "F.Cu")
		(at 263.186672 -77.636116)
		(property "Reference" "C5D28"
			(at 0 0 0)
			(layer "F.SilkS")
			(hide yes)
			(effects
				(font
					(size 1.27 1.27)
				)
			)
		)
		(property "Value" ""
			(at 0 0 0)
			(layer "F.Fab")
			(effects
				(font
					(size 1.27 1.27)
				)
			)
		)
		(duplicate_pad_numbers_are_jumpers no)
		(fp_poly
			(pts
				(xy -0.4953 -0.2032) (xy 0.4953 -0.2032) (xy 0.4953 1.6002) (xy -0.4953 1.6002)
			)
			(stroke
				(width 0)
				(type default)
			)
			(fill no)
			(layer "F.CrtYd")
		)
		(fp_line
			(start -0.4953 -0.2032)
			(end 0.4953 -0.2032)
			(stroke
				(width 0.1)
				(type default)
			)
			(layer "F.Fab")
		)
		(fp_line
			(start -0.4953 1.6002)
			(end -0.4953 -0.2032)
			(stroke
				(width 0.1)
				(type default)
			)
			(layer "F.Fab")
		)
		(fp_line
			(start 0.4953 -0.2032)
			(end 0.4953 1.6002)
			(stroke
				(width 0.1)
				(type default)
			)
			(layer "F.Fab")
		)
		(fp_line
			(start 0.4953 1.6002)
			(end -0.4953 1.6002)
			(stroke
				(width 0.1)
				(type default)
			)
			(layer "F.Fab")
		)
		(pad "1" smd rect
			(at 0 0)
			(size 0.762 0.889)
			(layers "F.Cu" "F.Mask" "F.Paste")
			(net "PVCCIN_CPU0")
		)
		(pad "2" smd rect
			(at 0 1.397)
			(size 0.762 0.889)
			(layers "F.Cu" "F.Mask" "F.Paste")
			(net "GND")
		)
		(zone
			(layer "F.Cu")
			(hatch none 0.5)
			(connect_pads
				(clearance 0)
			)
			(min_thickness 0.25)
			(keepout
				(tracks not_allowed)
				(vias allowed)
				(pads allowed)
				(copperpour not_allowed)
				(footprints allowed)
			)
			(placement
				(enabled no)
				(sheetname "")
			)
			(fill
				(thermal_gap 0.5)
				(thermal_bridge_width 0.5)
				(island_removal_mode 0)
			)
			(polygon
				(pts
					(xy 262.805672 -77.191616) (xy 263.567672 -77.191616) (xy 263.567672 -76.683616) (xy 262.805672 -76.683616)
				)
			)
		)
	)
)
